(kicad_pcb
	(version 20260206)
	(generator "pcbnew")
	(generator_version "10.0")
	(general
		(thickness 1.6)
		(legacy_teardrops no)
	)
	(paper "A4")
	(title_block
		(title "Bryce Canyon_R.DPB_16317-1_OCP.brd")
		(comment 1 "Bryce Canyon / footprints 417-423 of 2099")
	)
	(layers
		(0 "F.Cu" signal "TOP")
		(4 "In1.Cu" signal "L2GND")
		(6 "In2.Cu" signal "L3")
		(8 "In3.Cu" signal "L4VCC")
		(10 "In4.Cu" signal "L5VCC")
		(12 "In5.Cu" signal "L6")
		(14 "In6.Cu" signal "L7GND")
		(2 "B.Cu" signal "BOTTOM")
		(9 "F.Adhes" user "F.Adhesive")
		(11 "B.Adhes" user "B.Adhesive")
		(13 "F.Paste" user "Package Geometry/Pastemask Top")
		(15 "B.Paste" user "Package Geometry/Pastemask Bottom")
		(5 "F.SilkS" user "Ref Des/Silkscreen Top")
		(7 "B.SilkS" user "Ref Des/Silkscreen Bottom")
		(1 "F.Mask" user "Board Geometry/Soldermask Top")
		(3 "B.Mask" user "Board Geometry/Soldermask Bottom")
		(17 "Dwgs.User" user "User.Drawings")
		(19 "Cmts.User" user "User.Comments")
		(21 "Eco1.User" user "User.Eco1")
		(23 "Eco2.User" user "User.Eco2")
		(25 "Edge.Cuts" user "Board Geometry/Outline")
		(27 "Margin" user)
		(31 "F.CrtYd" user "Package Geometry/Place Bound Top")
		(29 "B.CrtYd" user "Package Geometry/Place Bound Bottom")
		(35 "F.Fab" user "Ref Des/Assembly Top")
		(33 "B.Fab" user "Ref Des/Assembly Bottom")
	)
	(footprint ""
		(layer "F.Cu")
		(at 475.742 -141.224 180)
		(property "Reference" "Q111"
			(at 0 0 180)
			(layer "F.SilkS")
			(hide yes)
			(effects
				(font
					(size 1.27 1.27)
				)
			)
		)
		(property "Value" "AO4406AL-GP"
			(at -3.707384 -1.5367 180)
			(unlocked yes)
			(layer "F.Fab")
			(hide yes)
			(effects
				(font
					(size 1.016 1.016)
					(thickness 0.1524)
				)
			)
		)
		(property "Device Type" "SOIC8H69"
			(at -3.707384 -3.0607 180)
			(unlocked yes)
			(layer "F.Fab")
			(hide yes)
			(effects
				(font
					(size 1.016 1.016)
					(thickness 0.1524)
				)
			)
		)
		(duplicate_pad_numbers_are_jumpers no)
		(fp_line
			(start 2.1336 1.4224)
			(end 2.1336 -1.4224)
			(stroke
				(width 0.1524)
				(type default)
			)
			(layer "F.SilkS")
		)
		(fp_line
			(start 2.1336 -1.4224)
			(end -2.7432 -1.4224)
			(stroke
				(width 0.1524)
				(type default)
			)
			(layer "F.SilkS")
		)
		(fp_line
			(start -2.1844 -0.0508)
			(end -2.7178 0.508)
			(stroke
				(width 0.1524)
				(type default)
			)
			(layer "F.SilkS")
		)
		(fp_line
			(start -2.6289 3.4417)
			(end -2.6289 1.4732)
			(stroke
				(width 0.381)
				(type default)
			)
			(layer "F.SilkS")
		)
		(fp_line
			(start -2.7178 -0.508)
			(end -2.1844 -0.0508)
			(stroke
				(width 0.1524)
				(type default)
			)
			(layer "F.SilkS")
		)
		(fp_line
			(start -2.7432 1.4224)
			(end 2.1336 1.4224)
			(stroke
				(width 0.1524)
				(type default)
			)
			(layer "F.SilkS")
		)
		(fp_line
			(start -2.7432 1.4224)
			(end -2.6416 1.4224)
			(stroke
				(width 0.1524)
				(type default)
			)
			(layer "F.SilkS")
		)
		(fp_line
			(start -2.7432 -1.4224)
			(end -2.7432 1.4224)
			(stroke
				(width 0.1524)
				(type default)
			)
			(layer "F.SilkS")
		)
		(fp_poly
			(pts
				(xy -2.2098 -1.4224) (xy -2.2098 1.4224) (xy 2.2098 1.4224) (xy 2.2098 -1.4224)
			)
			(stroke
				(width 0)
				(type default)
			)
			(fill yes)
			(layer "F.SilkS")
		)
		(fp_rect
			(start -2.450084 2.999994)
			(end 2.450084 -2.999994)
			(stroke
				(width 0)
				(type default)
			)
			(fill no)
			(layer "F.CrtYd")
		)
		(fp_poly
			(pts
				(xy -2.8194 3.6322) (xy -2.8194 -3.6322) (xy 2.8194 -3.6322) (xy 2.8194 1.18364) (xy 2.450084 1.18364)
				(xy 2.450084 -2.999994) (xy -2.450084 -2.999994) (xy -2.450084 2.999994) (xy 2.450084 2.999994)
				(xy 2.450084 1.18618) (xy 2.8194 1.18618) (xy 2.8194 3.6322)
			)
			(stroke
				(width 0)
				(type default)
			)
			(fill no)
			(layer "F.CrtYd")
		)
		(fp_rect
			(start -2.8194 3.6322)
			(end 2.8194 -3.6322)
			(stroke
				(width 0)
				(type default)
			)
			(fill no)
			(layer "F.Fab")
		)
		(pad "1" smd rect
			(at -1.905 2.54 180)
			(size 0.635 1.651)
			(layers "F.Cu" "F.Mask" "F.Paste")
			(net "P5V_HDD23")
		)
		(pad "2" smd rect
			(at -0.635 2.54 180)
			(size 0.635 1.651)
			(layers "F.Cu" "F.Mask" "F.Paste")
			(net "P5V_HDD23")
		)
		(pad "3" smd rect
			(at 0.635 2.54 180)
			(size 0.635 1.651)
			(layers "F.Cu" "F.Mask" "F.Paste")
			(net "P5V_HDD23")
		)
		(pad "4" smd rect
			(at 1.905 2.54 180)
			(size 0.635 1.651)
			(layers "F.Cu" "F.Mask" "F.Paste")
			(net "SW_HDD_P23")
		)
		(pad "5" smd rect
			(at 1.905 -2.54 180)
			(size 0.635 1.651)
			(layers "F.Cu" "F.Mask" "F.Paste")
			(net "P5V_B_4")
		)
		(pad "6" smd rect
			(at 0.635 -2.54 180)
			(size 0.635 1.651)
			(layers "F.Cu" "F.Mask" "F.Paste")
			(net "P5V_B_4")
		)
		(pad "7" smd rect
			(at -0.635 -2.54 180)
			(size 0.635 1.651)
			(layers "F.Cu" "F.Mask" "F.Paste")
			(net "P5V_B_4")
		)
		(pad "8" smd rect
			(at -1.905 -2.54 180)
			(size 0.635 1.651)
			(layers "F.Cu" "F.Mask" "F.Paste")
			(net "P5V_B_4")
		)
	)
	(footprint ""
		(layer "F.Cu")
		(at 46.736 -133.096 180)
		(property "Reference" "R385"
			(at 0 0 180)
			(layer "F.SilkS")
			(hide yes)
			(effects
				(font
					(size 1.27 1.27)
				)
			)
		)
		(property "Value" "200KR2F-L-GP"
			(at 0.064008 -3.993896 180)
			(unlocked yes)
			(layer "F.Fab")
			(hide yes)
			(effects
				(font
					(size 1.016 1.016)
					(thickness 0.1524)
				)
			)
		)
		(property "Device Type" "R402H16"
			(at 0.064008 -5.517896 180)
			(unlocked yes)
			(layer "F.Fab")
			(hide yes)
			(effects
				(font
					(size 1.016 1.016)
					(thickness 0.1524)
				)
			)
		)
		(duplicate_pad_numbers_are_jumpers no)
		(fp_line
			(start 0.508 -0.9398)
			(end -0.508 -0.9398)
			(stroke
				(width 0.1524)
				(type default)
			)
			(layer "F.SilkS")
		)
		(fp_line
			(start -0.508 -0.9398)
			(end -0.508 0.9398)
			(stroke
				(width 0.1524)
				(type default)
			)
			(layer "F.SilkS")
		)
		(fp_rect
			(start -0.508 0.9398)
			(end 0.508 -0.9398)
			(stroke
				(width 0)
				(type default)
			)
			(fill no)
			(layer "F.CrtYd")
		)
		(fp_rect
			(start -0.508 0.9398)
			(end 0.508 -0.9398)
			(stroke
				(width 0)
				(type default)
			)
			(fill no)
			(layer "F.Fab")
		)
		(pad "1" smd custom
			(at 0 -0.4445 180)
			(size 0.1397 0.1397)
			(layers "F.Cu" "F.Mask" "F.Paste")
			(net "SW_HDD_R13")
			(options
				(clearance outline)
				(anchor circle)
			)
			(primitives
				(gr_poly
					(pts
						(arc
							(start -0.1778 -0.2794)
							(mid -0.249642 -0.249642)
							(end -0.2794 -0.1778)
						)
						(arc
							(start -0.2794 0.1778)
							(mid -0.249642 0.249642)
							(end -0.1778 0.2794)
						)
						(arc
							(start 0.1778 0.2794)
							(mid 0.249642 0.249642)
							(end 0.2794 0.1778)
						)
						(arc
							(start 0.2794 -0.1778)
							(mid 0.249642 -0.249642)
							(end 0.1778 -0.2794)
						)
					)
					(width 0)
					(fill yes)
				)
			)
		)
		(pad "2" smd custom
			(at 0 0.4445 180)
			(size 0.1397 0.1397)
			(layers "F.Cu" "F.Mask" "F.Paste")
			(net "SW_HDD_N13")
			(options
				(clearance outline)
				(anchor circle)
			)
			(primitives
				(gr_poly
					(pts
						(arc
							(start -0.1778 -0.2794)
							(mid -0.249642 -0.249642)
							(end -0.2794 -0.1778)
						)
						(arc
							(start -0.2794 0.1778)
							(mid -0.249642 0.249642)
							(end -0.1778 0.2794)
						)
						(arc
							(start 0.1778 0.2794)
							(mid 0.249642 0.249642)
							(end 0.2794 0.1778)
						)
						(arc
							(start 0.2794 -0.1778)
							(mid 0.249642 -0.249642)
							(end 0.1778 -0.2794)
						)
					)
					(width 0)
					(fill yes)
				)
			)
		)
	)
	(footprint ""
		(layer "F.Cu")
		(at 168.9354 -99.7204 180)
		(property "Reference" "Q236"
			(at 0 0 180)
			(layer "F.SilkS")
			(hide yes)
			(effects
				(font
					(size 1.27 1.27)
				)
			)
		)
		(property "Value" "2N7002K-2-GP"
			(at 0.127 -8.9662 180)
			(unlocked yes)
			(layer "F.Fab")
			(hide yes)
			(effects
				(font
					(size 1.016 1.016)
					(thickness 0.1524)
				)
			)
		)
		(property "Device Type" "SOT23DGS2D4H44"
			(at 0.127 -10.4902 180)
			(unlocked yes)
			(layer "F.Fab")
			(hide yes)
			(effects
				(font
					(size 1.016 1.016)
					(thickness 0.1524)
				)
			)
		)
		(duplicate_pad_numbers_are_jumpers no)
		(fp_line
			(start 1.651 1.778)
			(end 1.651 -1.778)
			(stroke
				(width 0.1524)
				(type default)
			)
			(layer "F.SilkS")
		)
		(fp_line
			(start 1.651 -1.778)
			(end -1.651 -1.778)
			(stroke
				(width 0.1524)
				(type default)
			)
			(layer "F.SilkS")
		)
		(fp_line
			(start -1.651 1.778)
			(end 1.651 1.778)
			(stroke
				(width 0.1524)
				(type default)
			)
			(layer "F.SilkS")
		)
		(fp_line
			(start -1.651 -1.778)
			(end -1.651 1.778)
			(stroke
				(width 0.1524)
				(type default)
			)
			(layer "F.SilkS")
		)
		(fp_poly
			(pts
				(xy -1.778 1.8796) (xy -1.778 -1.8796) (xy 1.778 -1.8796) (xy 1.778 1.8796)
			)
			(stroke
				(width 0)
				(type default)
			)
			(fill no)
			(layer "F.CrtYd")
		)
		(fp_poly
			(pts
				(xy -1.778 1.8796) (xy -1.778 -1.8796) (xy 1.778 -1.8796) (xy 1.778 1.8796)
			)
			(stroke
				(width 0)
				(type default)
			)
			(fill no)
			(layer "F.Fab")
		)
		(pad "D" smd custom
			(at 0 -0.9525 180)
			(size 0.1905 0.1905)
			(layers "F.Cu" "F.Mask" "F.Paste")
			(net "FLT_HDD17_N")
			(options
				(clearance outline)
				(anchor circle)
			)
			(primitives
				(gr_poly
					(pts
						(arc
							(start -0.1778 0.5715)
							(mid -0.321484 0.511984)
							(end -0.381 0.3683)
						)
						(arc
							(start -0.381 -0.3683)
							(mid -0.321484 -0.511984)
							(end -0.1778 -0.5715)
						)
						(arc
							(start 0.1778 -0.5715)
							(mid 0.321484 -0.511984)
							(end 0.381 -0.3683)
						)
						(arc
							(start 0.381 0.3683)
							(mid 0.321484 0.511984)
							(end 0.1778 0.5715)
						)
					)
					(width 0)
					(fill yes)
				)
			)
		)
		(pad "G" smd custom
			(at -0.98425 0.9525 180)
			(size 0.1905 0.1905)
			(layers "F.Cu" "F.Mask" "F.Paste")
			(net "DRIVE_B_17_FLT_LED")
			(options
				(clearance outline)
				(anchor circle)
			)
			(primitives
				(gr_poly
					(pts
						(arc
							(start -0.1778 0.5715)
							(mid -0.321484 0.511984)
							(end -0.381 0.3683)
						)
						(arc
							(start -0.381 -0.3683)
							(mid -0.321484 -0.511984)
							(end -0.1778 -0.5715)
						)
						(arc
							(start 0.1778 -0.5715)
							(mid 0.321484 -0.511984)
							(end 0.381 -0.3683)
						)
						(arc
							(start 0.381 0.3683)
							(mid 0.321484 0.511984)
							(end 0.1778 0.5715)
						)
					)
					(width 0)
					(fill yes)
				)
			)
		)
		(pad "S" smd custom
			(at 0.98425 0.9525 180)
			(size 0.1905 0.1905)
			(layers "F.Cu" "F.Mask" "F.Paste")
			(net "GND")
			(options
				(clearance outline)
				(anchor circle)
			)
			(primitives
				(gr_poly
					(pts
						(arc
							(start -0.1778 0.5715)
							(mid -0.321484 0.511984)
							(end -0.381 0.3683)
						)
						(arc
							(start -0.381 -0.3683)
							(mid -0.321484 -0.511984)
							(end -0.1778 -0.5715)
						)
						(arc
							(start 0.1778 -0.5715)
							(mid 0.321484 -0.511984)
							(end 0.381 -0.3683)
						)
						(arc
							(start 0.381 0.3683)
							(mid 0.321484 0.511984)
							(end 0.1778 0.5715)
						)
					)
					(width 0)
					(fill yes)
				)
			)
		)
	)
	(footprint ""
		(layer "F.Cu")
		(at 308.110382 -332.979776 180)
		(property "Reference" "C38"
			(at 0 0 180)
			(layer "F.SilkS")
			(hide yes)
			(effects
				(font
					(size 1.27 1.27)
				)
			)
		)
		(property "Value" "SC1U16V3KX-5GP"
			(at 0 -2.8194 180)
			(unlocked yes)
			(layer "F.Fab")
			(hide yes)
			(effects
				(font
					(size 1.016 1.016)
					(thickness 0.1524)
				)
			)
		)
		(property "Device Type" "C603H36"
			(at 0 -4.3434 180)
			(unlocked yes)
			(layer "F.Fab")
			(hide yes)
			(effects
				(font
					(size 1.016 1.016)
					(thickness 0.1524)
				)
			)
		)
		(duplicate_pad_numbers_are_jumpers no)
		(fp_line
			(start 0.508 0)
			(end -0.508 0)
			(stroke
				(width 0.2032)
				(type default)
			)
			(layer "F.SilkS")
		)
		(fp_rect
			(start -0.5842 1.3335)
			(end 0.5842 -1.3335)
			(stroke
				(width 0)
				(type default)
			)
			(fill no)
			(layer "F.CrtYd")
		)
		(fp_rect
			(start -0.5842 1.3335)
			(end 0.5842 -1.3335)
			(stroke
				(width 0)
				(type default)
			)
			(fill no)
			(layer "F.Fab")
		)
		(pad "1" smd custom
			(at 0 -0.762 180)
			(size 0.2159 0.2159)
			(layers "F.Cu" "F.Mask" "F.Paste")
			(net "P3V3_IN")
			(options
				(clearance outline)
				(anchor circle)
			)
			(primitives
				(gr_poly
					(pts
						(arc
							(start -0.3302 -0.4318)
							(mid -0.402042 -0.402042)
							(end -0.4318 -0.3302)
						)
						(arc
							(start -0.4318 0.3302)
							(mid -0.402042 0.402042)
							(end -0.3302 0.4318)
						)
						(arc
							(start 0.3302 0.4318)
							(mid 0.402042 0.402042)
							(end 0.4318 0.3302)
						)
						(arc
							(start 0.4318 -0.3302)
							(mid 0.402042 -0.402042)
							(end 0.3302 -0.4318)
						)
					)
					(width 0)
					(fill yes)
				)
			)
		)
		(pad "2" smd custom
			(at 0 0.762 180)
			(size 0.2159 0.2159)
			(layers "F.Cu" "F.Mask" "F.Paste")
			(net "GND")
			(options
				(clearance outline)
				(anchor circle)
			)
			(primitives
				(gr_poly
					(pts
						(arc
							(start -0.3302 -0.4318)
							(mid -0.402042 -0.402042)
							(end -0.4318 -0.3302)
						)
						(arc
							(start -0.4318 0.3302)
							(mid -0.402042 0.402042)
							(end -0.3302 0.4318)
						)
						(arc
							(start 0.3302 0.4318)
							(mid 0.402042 0.402042)
							(end 0.4318 0.3302)
						)
						(arc
							(start 0.4318 -0.3302)
							(mid 0.402042 -0.402042)
							(end 0.3302 -0.4318)
						)
					)
					(width 0)
					(fill yes)
				)
			)
		)
	)
	(footprint ""
		(layer "F.Cu")
		(at 83.185 -146.939 -90)
		(property "Reference" "C213"
			(at 0 0 270)
			(layer "F.SilkS")
			(hide yes)
			(effects
				(font
					(size 1.27 1.27)
				)
			)
		)
		(property "Value" "SC10U16V6KX-2GP"
			(at -0.0762 -5.1308 270)
			(unlocked yes)
			(layer "F.Fab")
			(hide yes)
			(effects
				(font
					(size 1.016 1.016)
					(thickness 0.1524)
				)
			)
		)
		(property "Device Type" "C1206H71"
			(at -0.127 -6.6548 270)
			(unlocked yes)
			(layer "F.Fab")
			(hide yes)
			(effects
				(font
					(size 1.016 1.016)
					(thickness 0.1524)
				)
			)
		)
		(duplicate_pad_numbers_are_jumpers no)
		(fp_line
			(start -1.016 2.2352)
			(end -1.016 0.8382)
			(stroke
				(width 0.1524)
				(type default)
			)
			(layer "F.SilkS")
		)
		(fp_line
			(start 1.016 2.2352)
			(end -1.016 2.2352)
			(stroke
				(width 0.1524)
				(type default)
			)
			(layer "F.SilkS")
		)
		(fp_line
			(start 1.016 0.8382)
			(end 1.016 2.2352)
			(stroke
				(width 0.1524)
				(type default)
			)
			(layer "F.SilkS")
		)
		(fp_line
			(start -1.016 -0.8382)
			(end -1.016 -2.2352)
			(stroke
				(width 0.1524)
				(type default)
			)
			(layer "F.SilkS")
		)
		(fp_line
			(start -1.016 -2.2352)
			(end 1.016 -2.2352)
			(stroke
				(width 0.1524)
				(type default)
			)
			(layer "F.SilkS")
		)
		(fp_line
			(start 1.016 -2.2352)
			(end 1.016 -0.8382)
			(stroke
				(width 0.1524)
				(type default)
			)
			(layer "F.SilkS")
		)
		(fp_rect
			(start -1.0922 2.3114)
			(end 1.0922 -2.3114)
			(stroke
				(width 0)
				(type default)
			)
			(fill no)
			(layer "F.CrtYd")
		)
		(fp_poly
			(pts
				(xy 1.0922 -2.3114) (xy 1.0922 2.3114) (xy -1.0922 2.3114) (xy -1.0922 -2.3114)
			)
			(stroke
				(width 0)
				(type default)
			)
			(fill no)
			(layer "F.Fab")
		)
		(pad "1" smd rect
			(at 0 -1.397 270)
			(size 1.651 1.27)
			(layers "F.Cu" "F.Mask" "F.Paste")
			(net "P5V_HDD14")
		)
		(pad "2" smd rect
			(at 0 1.397 270)
			(size 1.651 1.27)
			(layers "F.Cu" "F.Mask" "F.Paste")
			(net "GND")
		)
	)
	(footprint ""
		(layer "F.Cu")
		(at 306.932076 -340.812882)
		(property "Reference" "R100"
			(at 0 0 0)
			(layer "F.SilkS")
			(hide yes)
			(effects
				(font
					(size 1.27 1.27)
				)
			)
		)
		(property "Value" "4K7R2F-GP"
			(at 0.064008 -3.993896 0)
			(unlocked yes)
			(layer "F.Fab")
			(hide yes)
			(effects
				(font
					(size 1.016 1.016)
					(thickness 0.1524)
				)
			)
		)
		(property "Device Type" "R402H16"
			(at 0.064008 -5.517896 0)
			(unlocked yes)
			(layer "F.Fab")
			(hide yes)
			(effects
				(font
					(size 1.016 1.016)
					(thickness 0.1524)
				)
			)
		)
		(duplicate_pad_numbers_are_jumpers no)
		(fp_line
			(start -0.508 -0.9398)
			(end -0.508 0.9398)
			(stroke
				(width 0.1524)
				(type default)
			)
			(layer "F.SilkS")
		)
		(fp_line
			(start 0.508 -0.9398)
			(end -0.508 -0.9398)
			(stroke
				(width 0.1524)
				(type default)
			)
			(layer "F.SilkS")
		)
		(fp_rect
			(start -0.508 0.9398)
			(end 0.508 -0.9398)
			(stroke
				(width 0)
				(type default)
			)
			(fill no)
			(layer "F.CrtYd")
		)
		(fp_rect
			(start -0.508 0.9398)
			(end 0.508 -0.9398)
			(stroke
				(width 0)
				(type default)
			)
			(fill no)
			(layer "F.Fab")
		)
		(pad "1" smd custom
			(at 0 -0.4445)
			(size 0.1397 0.1397)
			(layers "F.Cu" "F.Mask" "F.Paste")
			(net "P3V3_IN")
			(options
				(clearance outline)
				(anchor circle)
			)
			(primitives
				(gr_poly
					(pts
						(arc
							(start -0.1778 -0.2794)
							(mid -0.249642 -0.249642)
							(end -0.2794 -0.1778)
						)
						(arc
							(start -0.2794 0.1778)
							(mid -0.249642 0.249642)
							(end -0.1778 0.2794)
						)
						(arc
							(start 0.1778 0.2794)
							(mid 0.249642 0.249642)
							(end 0.2794 0.1778)
						)
						(arc
							(start 0.2794 -0.1778)
							(mid 0.249642 -0.249642)
							(end 0.1778 -0.2794)
						)
					)
					(width 0)
					(fill yes)
				)
			)
		)
		(pad "2" smd custom
			(at 0 0.4445)
			(size 0.1397 0.1397)
			(layers "F.Cu" "F.Mask" "F.Paste")
			(net "PWM_CAMP_SEL1")
			(options
				(clearance outline)
				(anchor circle)
			)
			(primitives
				(gr_poly
					(pts
						(arc
							(start -0.1778 -0.2794)
							(mid -0.249642 -0.249642)
							(end -0.2794 -0.1778)
						)
						(arc
							(start -0.2794 0.1778)
							(mid -0.249642 0.249642)
							(end -0.1778 0.2794)
						)
						(arc
							(start 0.1778 0.2794)
							(mid 0.249642 0.249642)
							(end 0.2794 0.1778)
						)
						(arc
							(start 0.2794 -0.1778)
							(mid 0.249642 -0.249642)
							(end 0.1778 -0.2794)
						)
					)
					(width 0)
					(fill yes)
				)
			)
		)
	)
	(footprint ""
		(layer "F.Cu")
		(at 82.042 -150.622 90)
		(property "Reference" "R393"
			(at 0 0 90)
			(layer "F.SilkS")
			(hide yes)
			(effects
				(font
					(size 1.27 1.27)
				)
			)
		)
		(property "Value" "2R6F-GP"
			(at -0.0508 -4.8514 90)
			(unlocked yes)
			(layer "F.Fab")
			(hide yes)
			(effects
				(font
					(size 1.016 1.016)
					(thickness 0.1524)
				)
			)
		)
		(property "Device Type" "R1206H26"
			(at 0 -6.3754 90)
			(unlocked yes)
			(layer "F.Fab")
			(hide yes)
			(effects
				(font
					(size 1.016 1.016)
					(thickness 0.1524)
				)
			)
		)
		(duplicate_pad_numbers_are_jumpers no)
		(fp_line
			(start 1.016 -2.2352)
			(end 1.016 2.2352)
			(stroke
				(width 0.1524)
				(type default)
			)
			(layer "F.SilkS")
		)
		(fp_line
			(start -1.016 -2.2352)
			(end 1.016 -2.2352)
			(stroke
				(width 0.1524)
				(type default)
			)
			(layer "F.SilkS")
		)
		(fp_line
			(start 1.016 2.2352)
			(end -1.016 2.2352)
			(stroke
				(width 0.1524)
				(type default)
			)
			(layer "F.SilkS")
		)
		(fp_line
			(start -1.016 2.2352)
			(end -1.016 -2.2352)
			(stroke
				(width 0.1524)
				(type default)
			)
			(layer "F.SilkS")
		)
		(fp_rect
			(start -1.0922 2.3114)
			(end 1.0922 -2.3114)
			(stroke
				(width 0)
				(type default)
			)
			(fill no)
			(layer "F.CrtYd")
		)
		(fp_poly
			(pts
				(xy -1.0922 -2.3114) (xy 1.0922 -2.3114) (xy 1.0922 2.3114) (xy -1.0922 2.3114)
			)
			(stroke
				(width 0)
				(type default)
			)
			(fill no)
			(layer "F.Fab")
		)
		(pad "1" smd rect
			(at 0 -1.397 90)
			(size 1.651 1.27)
			(layers "F.Cu" "F.Mask" "F.Paste")
			(net "P12V_HDD14")
		)
		(pad "2" smd rect
			(at 0 1.397 90)
			(size 1.651 1.27)
			(layers "F.Cu" "F.Mask" "F.Paste")
			(net "12V_PRE_14")
		)
	)
)
